(kicad_pcb
	(version 20241229)
	(generator "pcbnew")
	(generator_version "9.0")
	(general
		(thickness 1.599998)
		(legacy_teardrops no)
	)
	(paper "A4")
	(title_block
		(date "2023-02-12")
		(rev "1.1.5")
		(comment 9 "footprints 130-132 of 473")
	)
	(layers
		(0 "F.Cu" signal)
		(4 "In1.Cu" power "In1.GND")
		(6 "In2.Cu" signal)
		(8 "In3.Cu" power "In3.GND")
		(10 "In4.Cu" power "In4.VCC")
		(12 "In5.Cu" signal)
		(14 "In6.Cu" power "In6.VCC")
		(2 "B.Cu" signal)
		(9 "F.Adhes" user "F.Adhesive")
		(11 "B.Adhes" user "B.Adhesive")
		(13 "F.Paste" user)
		(15 "B.Paste" user)
		(5 "F.SilkS" user "F.Silkscreen")
		(7 "B.SilkS" user "B.Silkscreen")
		(1 "F.Mask" user)
		(3 "B.Mask" user)
		(17 "Dwgs.User" user "User.Drawings")
		(19 "Cmts.User" user "User.Comments")
		(21 "Eco1.User" user "User.Eco1")
		(23 "Eco2.User" user "User.Eco2")
		(25 "Edge.Cuts" user)
		(27 "Margin" user)
		(31 "F.CrtYd" user "F.Courtyard")
		(29 "B.CrtYd" user "B.Courtyard")
		(35 "F.Fab" user)
		(33 "B.Fab" user)
	)
	(footprint "antmicro-footprints:oshw-logo"
		(layer "F.Cu")
		(at 191.386328 58.320008)
		(descr "OSHW Logo")
		(tags "OSHW Logo")
		(property "Reference" "N2"
			(at 0 -4.4 0)
			(layer "F.SilkS")
			(hide yes)
			(effects
				(font
					(size 0.7 0.7)
					(thickness 0.15)
				)
				(justify left bottom)
			)
		)
		(property "Value" "oshw_logo"
			(at 0 -3.4 0)
			(layer "F.Fab")
			(hide yes)
			(effects
				(font
					(size 0.7 0.7)
					(thickness 0.15)
				)
				(justify left bottom)
			)
		)
		(property "Author" "Antmicro"
			(at 0 0 0)
			(layer "F.Fab")
			(hide yes)
			(effects
				(font
					(size 1 1)
					(thickness 0.15)
				)
			)
		)
		(property "License" "Apache-2.0"
			(at 0 0 0)
			(layer "F.Fab")
			(hide yes)
			(effects
				(font
					(size 1 1)
					(thickness 0.15)
				)
			)
		)
		(property "MPN" ""
			(at 0 0 0)
			(layer "F.Fab")
			(hide yes)
			(effects
				(font
					(size 1 1)
					(thickness 0.15)
				)
			)
		)
		(property "Manufacturer" ""
			(at 0 0 0)
			(layer "F.Fab")
			(hide yes)
			(effects
				(font
					(size 1 1)
					(thickness 0.15)
				)
			)
		)
		(sheetfile "lpddr4-test-board.kicad_sch")
		(attr exclude_from_pos_files)
	)
	(footprint "antmicro-footprints:LED_0603_1608Metric_G"
		(layer "F.Cu")
		(at 205.286328 84.820008 180)
		(descr "LED SMD 0603 Green")
		(tags "LED SMD 0603 Green")
		(property "Reference" "D8"
			(at 0.786328 0.620008 180)
			(layer "F.SilkS")
			(effects
				(font
					(size 0.7 0.7)
					(thickness 0.15)
				)
				(justify left bottom)
			)
		)
		(property "Value" "LED_G_0603_KP-1608CGCK"
			(at 0 1.6 180)
			(layer "F.Fab")
			(effects
				(font
					(size 0.7 0.7)
					(thickness 0.15)
				)
				(justify left bottom)
			)
		)
		(property "Author" "Antmicro"
			(at 410.572656 169.640016 0)
			(layer "F.Fab")
			(hide yes)
			(effects
				(font
					(size 1 1)
					(thickness 0.15)
				)
			)
		)
		(property "License" "Apache-2.0"
			(at 410.572656 169.640016 0)
			(layer "F.Fab")
			(hide yes)
			(effects
				(font
					(size 1 1)
					(thickness 0.15)
				)
			)
		)
		(property "MPN" "KP-1608CGCK"
			(at 410.572656 169.640016 0)
			(layer "F.Fab")
			(hide yes)
			(effects
				(font
					(size 1 1)
					(thickness 0.15)
				)
			)
		)
		(property "Manufacturer" "Kingbright"
			(at 410.572656 169.640016 0)
			(layer "F.Fab")
			(hide yes)
			(effects
				(font
					(size 1 1)
					(thickness 0.15)
				)
			)
		)
		(sheetname "Config SPI flash")
		(sheetfile "config-spi.kicad_sch")
		(attr smd)
		(fp_line
			(start 1.25 0.32)
			(end 1.25 -0.32)
			(stroke
				(width 0.15)
				(type solid)
			)
			(layer "F.SilkS")
		)
		(fp_line
			(start 0.093672 -8e-06)
			(end 0.293672 -8e-06)
			(stroke
				(width 0.1)
				(type solid)
			)
			(layer "F.SilkS")
		)
		(fp_line
			(start 0.093672 -8e-06)
			(end -0.106328 0.199992)
			(stroke
				(width 0.1)
				(type solid)
			)
			(layer "F.SilkS")
		)
		(fp_line
			(start 0.093672 -0.200008)
			(end 0.093672 0.199992)
			(stroke
				(width 0.1)
				(type solid)
			)
			(layer "F.SilkS")
		)
		(fp_line
			(start -0.106328 -8e-06)
			(end -0.29 0)
			(stroke
				(width 0.1)
				(type solid)
			)
			(layer "F.SilkS")
		)
		(fp_line
			(start -0.106328 -0.200008)
			(end 0.093672 -8e-06)
			(stroke
				(width 0.1)
				(type solid)
			)
			(layer "F.SilkS")
		)
		(fp_line
			(start -0.106328 -0.200008)
			(end -0.106328 0.199992)
			(stroke
				(width 0.1)
				(type solid)
			)
			(layer "F.SilkS")
		)
		(fp_line
			(start -0.27 0.351)
			(end 0.27 0.351)
			(stroke
				(width 0.15)
				(type solid)
			)
			(layer "F.SilkS")
		)
		(fp_line
			(start -0.27 -0.35)
			(end 0.27 -0.35)
			(stroke
				(width 0.15)
				(type solid)
			)
			(layer "F.SilkS")
		)
		(fp_rect
			(start 1.26 0.65)
			(end -1.26 -0.65)
			(stroke
				(width 0.05)
				(type solid)
			)
			(fill no)
			(layer "F.CrtYd")
		)
		(fp_line
			(start 0.199 0.202)
			(end 0.199 -0.1)
			(stroke
				(width 0.15)
				(type solid)
			)
			(layer "F.Fab")
		)
		(fp_line
			(start 0.199 0)
			(end 0.597 0)
			(stroke
				(width 0.15)
				(type solid)
			)
			(layer "F.Fab")
		)
		(fp_line
			(start 0.199 -0.2)
			(end 0.199 -0.1)
			(stroke
				(width 0.15)
				(type solid)
			)
			(layer "F.Fab")
		)
		(fp_line
			(start 0.101 0)
			(end -0.201 -0.2)
			(stroke
				(width 0.15)
				(type solid)
			)
			(layer "F.Fab")
		)
		(fp_line
			(start -0.201 0.202)
			(end 0.101 0)
			(stroke
				(width 0.15)
				(type solid)
			)
			(layer "F.Fab")
		)
		(fp_line
			(start -0.201 0)
			(end -0.201 0.202)
			(stroke
				(width 0.15)
				(type solid)
			)
			(layer "F.Fab")
		)
		(fp_line
			(start -0.201 -0.2)
			(end -0.201 0)
			(stroke
				(width 0.15)
				(type solid)
			)
			(layer "F.Fab")
		)
		(fp_line
			(start -0.599 0)
			(end -0.201 0)
			(stroke
				(width 0.15)
				(type solid)
			)
			(layer "F.Fab")
		)
		(fp_rect
			(start -0.848 -0.4)
			(end 0.85 0.402)
			(stroke
				(width 0.15)
				(type solid)
			)
			(fill no)
			(layer "F.Fab")
		)
		(pad "1" smd rect
			(at -0.75 0)
			(size 0.8 0.8)
			(layers "F.Cu" "F.Mask" "F.Paste")
			(net 459 "3V3_SYS")
			(pinfunction "1")
			(pintype "passive")
		)
		(pad "2" smd rect
			(at 0.75 0)
			(size 0.8 0.8)
			(layers "F.Cu" "F.Mask" "F.Paste")
			(net 54 "Net-(D8-Pad2)")
			(pinfunction "2")
			(pintype "passive")
		)
	)
	(footprint "antmicro-footprints:C_0402_1005Metric"
		(layer "F.Cu")
		(at 191.386328 101.374306 90)
		(descr "Capacitor SMD 0402")
		(tags "capacitor SMD 0402")
		(property "Reference" "C111"
			(at 2.974306 0.413672 90)
			(layer "F.SilkS")
			(effects
				(font
					(size 0.7 0.7)
					(thickness 0.15)
				)
				(justify left bottom)
			)
		)
		(property "Value" "C_10n_0402"
			(at 0 1.4 90)
			(layer "F.Fab")
			(effects
				(font
					(size 0.7 0.7)
					(thickness 0.15)
				)
				(justify left bottom)
			)
		)
		(property "Description" " "
			(at 0 0 90)
			(layer "F.Fab")
			(hide yes)
			(effects
				(font
					(size 1.27 1.27)
					(thickness 0.15)
				)
			)
		)
		(property "Author" "Antmicro"
			(at 292.760634 -90.012022 0)
			(layer "F.Fab")
			(hide yes)
			(effects
				(font
					(size 1 1)
					(thickness 0.15)
				)
			)
		)
		(property "Dielectric" "X7R"
			(at 292.760634 -90.012022 0)
			(layer "F.Fab")
			(hide yes)
			(effects
				(font
					(size 1 1)
					(thickness 0.15)
				)
			)
		)
		(property "License" "Apache-2.0"
			(at 292.760634 -90.012022 0)
			(layer "F.Fab")
			(hide yes)
			(effects
				(font
					(size 1 1)
					(thickness 0.15)
				)
			)
		)
		(property "MPN" "GRM155R71H103KA88D"
			(at 292.760634 -90.012022 0)
			(layer "F.Fab")
			(hide yes)
			(effects
				(font
					(size 1 1)
					(thickness 0.15)
				)
			)
		)
		(property "Manufacturer" "Murata"
			(at 292.760634 -90.012022 0)
			(layer "F.Fab")
			(hide yes)
			(effects
				(font
					(size 1 1)
					(thickness 0.15)
				)
			)
		)
		(property "Val" "10n"
			(at 292.760634 -90.012022 0)
			(layer "F.Fab")
			(hide yes)
			(effects
				(font
					(size 1 1)
					(thickness 0.15)
				)
			)
		)
		(property "Voltage" "50V"
			(at 292.760634 -90.012022 0)
			(layer "F.Fab")
			(hide yes)
			(effects
				(font
					(size 1 1)
					(thickness 0.15)
				)
			)
		)
		(sheetname "Ethernet")
		(sheetfile "ethernet.kicad_sch")
		(attr smd)
		(fp_rect
			(start -0.94 -0.47)
			(end 0.94 0.47)
			(stroke
				(width 0.05)
				(type solid)
			)
			(fill no)
			(layer "F.CrtYd")
		)
		(fp_rect
			(start -0.499 -0.249)
			(end 0.499 0.249)
			(stroke
				(width 0.15)
				(type solid)
			)
			(fill no)
			(layer "F.Fab")
		)
		(pad "1" smd roundrect
			(at -0.484 0 90)
			(size 0.59 0.64)
			(layers "F.Cu" "F.Mask" "F.Paste")
			(roundrect_rratio 0.25)
			(net 530 "/Ethernet/AVDDL_PLL")
			(pintype "passive")
		)
		(pad "2" smd roundrect
			(at 0.484 0 90)
			(size 0.59 0.64)
			(layers "F.Cu" "F.Mask" "F.Paste")
			(roundrect_rratio 0.25)
			(net 5 "GND")
			(pintype "passive")
		)
	)
)
